FILE_TYPE = CONNECTIVITY;
{Allegro Design Entry HDL 17.2-2016 S081 (4005846) 1/11/2022}
"PAGE_NUMBER" = 64;
0"NC";
1"UPI_CPU1_CPU0_P1P0_DP<23:0>";
2"UPI_CPU1_CPU0_P1P0_DN<23:0>";
3"UPI_CPU0_CPU1_P0P1_DP<23:0>";
4"UPI_CPU0_CPU1_P0P1_DN<23:0>";
5"UPI_CPU0_CPU1_P0P1_DN<23>";
6"UPI_CPU0_CPU1_P0P1_DN<22>";
7"UPI_CPU0_CPU1_P0P1_DN<21>";
8"UPI_CPU0_CPU1_P0P1_DN<20>";
9"UPI_CPU0_CPU1_P0P1_DN<19>";
10"UPI_CPU0_CPU1_P0P1_DN<18>";
11"UPI_CPU0_CPU1_P0P1_DN<17>";
12"UPI_CPU0_CPU1_P0P1_DN<16>";
13"UPI_CPU0_CPU1_P0P1_DN<15>";
14"UPI_CPU0_CPU1_P0P1_DN<14>";
15"UPI_CPU0_CPU1_P0P1_DN<13>";
16"UPI_CPU0_CPU1_P0P1_DN<12>";
17"UPI_CPU0_CPU1_P0P1_DN<11>";
18"UPI_CPU0_CPU1_P0P1_DN<10>";
19"UPI_CPU0_CPU1_P0P1_DN<9>";
20"UPI_CPU0_CPU1_P0P1_DN<8>";
21"UPI_CPU0_CPU1_P0P1_DN<7>";
22"UPI_CPU0_CPU1_P0P1_DN<6>";
23"UPI_CPU0_CPU1_P0P1_DN<5>";
24"UPI_CPU0_CPU1_P0P1_DN<4>";
25"UPI_CPU0_CPU1_P0P1_DN<3>";
26"UPI_CPU0_CPU1_P0P1_DN<2>";
27"UPI_CPU0_CPU1_P0P1_DN<1>";
28"UPI_CPU0_CPU1_P0P1_DN<0>";
29"UPI_CPU0_CPU1_P0P1_DP<23>";
30"UPI_CPU0_CPU1_P0P1_DP<22>";
31"UPI_CPU0_CPU1_P0P1_DP<21>";
32"UPI_CPU0_CPU1_P0P1_DP<20>";
33"UPI_CPU0_CPU1_P0P1_DP<19>";
34"UPI_CPU0_CPU1_P0P1_DP<18>";
35"UPI_CPU0_CPU1_P0P1_DP<17>";
36"UPI_CPU0_CPU1_P0P1_DP<16>";
37"UPI_CPU0_CPU1_P0P1_DP<15>";
38"UPI_CPU0_CPU1_P0P1_DP<14>";
39"UPI_CPU0_CPU1_P0P1_DP<13>";
40"UPI_CPU0_CPU1_P0P1_DP<12>";
41"UPI_CPU0_CPU1_P0P1_DP<11>";
42"UPI_CPU0_CPU1_P0P1_DP<10>";
43"UPI_CPU0_CPU1_P0P1_DP<9>";
44"UPI_CPU0_CPU1_P0P1_DP<8>";
45"UPI_CPU0_CPU1_P0P1_DP<7>";
46"UPI_CPU0_CPU1_P0P1_DP<6>";
47"UPI_CPU0_CPU1_P0P1_DP<5>";
48"UPI_CPU0_CPU1_P0P1_DP<4>";
49"UPI_CPU0_CPU1_P0P1_DP<3>";
50"UPI_CPU0_CPU1_P0P1_DP<2>";
51"UPI_CPU0_CPU1_P0P1_DP<1>";
52"UPI_CPU0_CPU1_P0P1_DP<0>";
53"UPI_CPU1_CPU0_P1P0_DN<23>";
54"UPI_CPU1_CPU0_P1P0_DN<22>";
55"UPI_CPU1_CPU0_P1P0_DN<21>";
56"UPI_CPU1_CPU0_P1P0_DN<20>";
57"UPI_CPU1_CPU0_P1P0_DN<19>";
58"UPI_CPU1_CPU0_P1P0_DN<18>";
59"UPI_CPU1_CPU0_P1P0_DN<17>";
60"UPI_CPU1_CPU0_P1P0_DN<16>";
61"UPI_CPU1_CPU0_P1P0_DN<15>";
62"UPI_CPU1_CPU0_P1P0_DN<14>";
63"UPI_CPU1_CPU0_P1P0_DN<13>";
64"UPI_CPU1_CPU0_P1P0_DN<12>";
65"UPI_CPU1_CPU0_P1P0_DN<11>";
66"UPI_CPU1_CPU0_P1P0_DN<10>";
67"UPI_CPU1_CPU0_P1P0_DN<9>";
68"UPI_CPU1_CPU0_P1P0_DN<8>";
69"UPI_CPU1_CPU0_P1P0_DN<7>";
70"UPI_CPU1_CPU0_P1P0_DN<6>";
71"UPI_CPU1_CPU0_P1P0_DN<5>";
72"UPI_CPU1_CPU0_P1P0_DN<4>";
73"UPI_CPU1_CPU0_P1P0_DN<3>";
74"UPI_CPU1_CPU0_P1P0_DN<2>";
75"UPI_CPU1_CPU0_P1P0_DN<1>";
76"UPI_CPU1_CPU0_P1P0_DN<0>";
77"UPI_CPU1_CPU0_P1P0_DP<23>";
78"UPI_CPU1_CPU0_P1P0_DP<22>";
79"UPI_CPU1_CPU0_P1P0_DP<21>";
80"UPI_CPU1_CPU0_P1P0_DP<20>";
81"UPI_CPU1_CPU0_P1P0_DP<19>";
82"UPI_CPU1_CPU0_P1P0_DP<18>";
83"UPI_CPU1_CPU0_P1P0_DP<17>";
84"UPI_CPU1_CPU0_P1P0_DP<16>";
85"UPI_CPU1_CPU0_P1P0_DP<15>";
86"UPI_CPU1_CPU0_P1P0_DP<14>";
87"UPI_CPU1_CPU0_P1P0_DP<13>";
88"UPI_CPU1_CPU0_P1P0_DP<12>";
89"UPI_CPU1_CPU0_P1P0_DP<11>";
90"UPI_CPU1_CPU0_P1P0_DP<10>";
91"UPI_CPU1_CPU0_P1P0_DP<9>";
92"UPI_CPU1_CPU0_P1P0_DP<8>";
93"UPI_CPU1_CPU0_P1P0_DP<7>";
94"UPI_CPU1_CPU0_P1P0_DP<6>";
95"UPI_CPU1_CPU0_P1P0_DP<5>";
96"UPI_CPU1_CPU0_P1P0_DP<4>";
97"UPI_CPU1_CPU0_P1P0_DP<3>";
98"UPI_CPU1_CPU0_P1P0_DP<2>";
99"UPI_CPU1_CPU0_P1P0_DP<1>";
100"UPI_CPU1_CPU0_P1P0_DP<0>";
%"TAP"
"1","(-100,3875)","2","standard","I102";
;
CDS_LIB"standard"
BODY_TYPE"PLUMBING"
HDL_TAP"TRUE";
"B \NAC \NWC"3;
"S \NAC"
BN"22"30;
%"TAP"
"1","(-100,3825)","2","standard","I103";
;
CDS_LIB"standard"
BODY_TYPE"PLUMBING"
HDL_TAP"TRUE";
"B \NAC \NWC"3;
"S \NAC"
BN"21"31;
%"TAP"
"1","(-100,3775)","2","standard","I104";
;
CDS_LIB"standard"
BODY_TYPE"PLUMBING"
HDL_TAP"TRUE";
"B \NAC \NWC"3;
"S \NAC"
BN"20"32;
%"TAP"
"1","(-100,3525)","2","standard","I105";
;
CDS_LIB"standard"
BODY_TYPE"PLUMBING"
HDL_TAP"TRUE";
"B \NAC \NWC"3;
"S \NAC"
BN"15"37;
%"TAP"
"1","(-100,3425)","2","standard","I106";
;
CDS_LIB"standard"
BODY_TYPE"PLUMBING"
HDL_TAP"TRUE";
"B \NAC \NWC"3;
"S \NAC"
BN"13"39;
%"TAP"
"1","(-100,3375)","2","standard","I107";
;
CDS_LIB"standard"
BODY_TYPE"PLUMBING"
HDL_TAP"TRUE";
"B \NAC \NWC"3;
"S \NAC"
BN"12"40;
%"TAP"
"1","(-100,2475)","2","standard","I108";
;
CDS_LIB"standard"
BODY_TYPE"PLUMBING"
HDL_TAP"TRUE";
"B \NAC \NWC"4;
"S \NAC"
BN"19"9;
%"TAP"
"1","(-100,2425)","2","standard","I109";
;
CDS_LIB"standard"
BODY_TYPE"PLUMBING"
HDL_TAP"TRUE";
"B \NAC \NWC"4;
"S \NAC"
BN"18"10;
%"TAP"
"1","(-100,2375)","2","standard","I110";
;
CDS_LIB"standard"
BODY_TYPE"PLUMBING"
HDL_TAP"TRUE";
"B \NAC \NWC"4;
"S \NAC"
BN"17"11;
%"TAP"
"1","(-100,2325)","2","standard","I111";
;
CDS_LIB"standard"
BODY_TYPE"PLUMBING"
HDL_TAP"TRUE";
"B \NAC \NWC"4;
"S \NAC"
BN"16"12;
%"TAP"
"1","(-100,2225)","2","standard","I112";
;
CDS_LIB"standard"
BODY_TYPE"PLUMBING"
HDL_TAP"TRUE";
"B \NAC \NWC"4;
"S \NAC"
BN"14"14;
%"TAP"
"1","(-100,2075)","2","standard","I113";
;
CDS_LIB"standard"
BODY_TYPE"PLUMBING"
HDL_TAP"TRUE";
"B \NAC \NWC"4;
"S \NAC"
BN"11"17;
%"TAP"
"1","(-100,2025)","2","standard","I114";
;
CDS_LIB"standard"
BODY_TYPE"PLUMBING"
HDL_TAP"TRUE";
"B \NAC \NWC"4;
"S \NAC"
BN"10"18;
%"TAP"
"1","(-100,1975)","2","standard","I115";
;
CDS_LIB"standard"
BODY_TYPE"PLUMBING"
HDL_TAP"TRUE";
"B \NAC \NWC"4;
"S \NAC"
BN"9"19;
%"TAP"
"1","(-100,1925)","2","standard","I116";
;
CDS_LIB"standard"
BODY_TYPE"PLUMBING"
HDL_TAP"TRUE";
"B \NAC \NWC"4;
"S \NAC"
BN"8"20;
%"TAP"
"1","(-100,1875)","2","standard","I117";
;
CDS_LIB"standard"
BODY_TYPE"PLUMBING"
HDL_TAP"TRUE";
"B \NAC \NWC"4;
"S \NAC"
BN"7"21;
%"TAP"
"1","(-100,1825)","2","standard","I118";
;
CDS_LIB"standard"
BODY_TYPE"PLUMBING"
HDL_TAP"TRUE";
"B \NAC \NWC"4;
"S \NAC"
BN"6"22;
%"TAP"
"1","(-100,1775)","2","standard","I119";
;
CDS_LIB"standard"
BODY_TYPE"PLUMBING"
HDL_TAP"TRUE";
"B \NAC \NWC"4;
"S \NAC"
BN"5"23;
%"TAP"
"1","(-100,1725)","2","standard","I120";
;
CDS_LIB"standard"
BODY_TYPE"PLUMBING"
HDL_TAP"TRUE";
"B \NAC \NWC"4;
"S \NAC"
BN"4"24;
%"TAP"
"1","(-100,1675)","2","standard","I121";
;
CDS_LIB"standard"
BODY_TYPE"PLUMBING"
HDL_TAP"TRUE";
"B \NAC \NWC"4;
"S \NAC"
BN"3"25;
%"TAP"
"1","(-100,1625)","2","standard","I122";
;
CDS_LIB"standard"
BODY_TYPE"PLUMBING"
HDL_TAP"TRUE";
"B \NAC \NWC"4;
"S \NAC"
BN"2"26;
%"TAP"
"1","(-100,1575)","2","standard","I123";
;
CDS_LIB"standard"
BODY_TYPE"PLUMBING"
HDL_TAP"TRUE";
"B \NAC \NWC"4;
"S \NAC"
BN"1"27;
%"TAP"
"1","(-100,1525)","2","standard","I124";
;
CDS_LIB"standard"
BODY_TYPE"PLUMBING"
HDL_TAP"TRUE";
"B \NAC \NWC"4;
"S \NAC"
BN"0"28;
%"TAP"
"1","(-100,2675)","2","standard","I125";
;
CDS_LIB"standard"
BODY_TYPE"PLUMBING"
HDL_TAP"TRUE";
"B \NAC \NWC"4;
"S \NAC"
BN"23"5;
%"TAP"
"1","(-100,2125)","2","standard","I15";
;
CDS_LIB"standard"
BODY_TYPE"PLUMBING"
HDL_TAP"TRUE";
"B \NAC \NWC"4;
"S \NAC"
BN"12"16;
%"TAP"
"1","(-100,2175)","2","standard","I16";
;
CDS_LIB"standard"
BODY_TYPE"PLUMBING"
HDL_TAP"TRUE";
"B \NAC \NWC"4;
"S \NAC"
BN"13"15;
%"TAP"
"1","(-100,2275)","2","standard","I19";
;
CDS_LIB"standard"
BODY_TYPE"PLUMBING"
HDL_TAP"TRUE";
"B \NAC \NWC"4;
"S \NAC"
BN"15"13;
%"SOCKET4677_AZIF0045P001C01CS"
"23","(1600,2725)","0","pure_quanta","I21";
;
PART_NUMBER"DGA^7000023"
VALUE"SOCKET4677_AZIF0045-P001C01CS"
MATERIAL"IO"
PART_TYPE"SMLF"
$LOCATION"U1"
CDS_LMAN_SYM_OUTLINE"-1050,1350,1050,-1350"
NEEDS_NO_SIZE"TRUE"
CDS_LIB"pure_quanta"
CDS_LOCATION"U1"
$SEC"23"
CDS_SEC"23";
"UPI1_TX_DP0"
$PN"EE5"100;
"UPI1_TX_DP1"
$PN"ED6"99;
"UPI1_TX_DP2"
$PN"EA5"98;
"UPI1_TX_DP3"
$PN"DW7"97;
"UPI1_TX_DP4"
$PN"DU5"96;
"UPI1_TX_DP5"
$PN"DR7"95;
"UPI1_TX_DP6"
$PN"DN5"94;
"UPI1_TX_DP7"
$PN"DM6"93;
"UPI1_TX_DP8"
$PN"DJ5"92;
"UPI1_TX_DP9"
$PN"DG7"91;
"UPI1_TX_DP10"
$PN"DF6"90;
"UPI1_TX_DP11"
$PN"DC7"89;
"UPI1_TX_DP12"
$PN"DB6"88;
"UPI1_TX_DP13"
$PN"CW7"87;
"UPI1_TX_DP14"
$PN"CV6"86;
"UPI1_TX_DP15"
$PN"CR7"85;
"UPI1_TX_DP16"
$PN"CP6"84;
"UPI1_TX_DP17"
$PN"CL7"83;
"UPI1_TX_DP18"
$PN"CK6"82;
"UPI1_TX_DP19"
$PN"CG7"81;
"UPI1_TX_DP20"
$PN"CF6"80;
"UPI1_TX_DP21"
$PN"CC7"79;
"UPI1_TX_DP22"
$PN"CB6"78;
"UPI1_TX_DP23"
$PN"BW7"77;
"UPI1_TX_DN0"
$PN"EF6"76;
"UPI1_TX_DN1"
$PN"EC7"75;
"UPI1_TX_DN2"
$PN"EB6"74;
"UPI1_TX_DN3"
$PN"DY6"73;
"UPI1_TX_DN4"
$PN"DV6"72;
"UPI1_TX_DN5"
$PN"DT6"71;
"UPI1_TX_DN6"
$PN"DP6"70;
"UPI1_TX_DN7"
$PN"DL7"69;
"UPI1_TX_DN8"
$PN"DK6"68;
"UPI1_TX_DN9"
$PN"DH6"67;
"UPI1_TX_DN10"
$PN"DE5"66;
"UPI1_TX_DN11"
$PN"DD6"65;
"UPI1_TX_DN12"
$PN"DA5"64;
"UPI1_TX_DN13"
$PN"CY6"63;
"UPI1_TX_DN14"
$PN"CU5"62;
"UPI1_TX_DN15"
$PN"CT6"61;
"UPI1_TX_DN16"
$PN"CN5"60;
"UPI1_TX_DN17"
$PN"CM6"59;
"UPI1_TX_DN18"
$PN"CJ5"58;
"UPI1_TX_DN19"
$PN"CH6"57;
"UPI1_TX_DN20"
$PN"CE5"56;
"UPI1_TX_DN21"
$PN"CD6"55;
"UPI1_TX_DN22"
$PN"CA5"54;
"UPI1_TX_DN23"
$PN"BY6"53;
"UPI1_RX_DP0"
$PN"EJ3"52;
"UPI1_RX_DP1"
$PN"EG3"51;
"UPI1_RX_DP2"
$PN"EC3"50;
"UPI1_RX_DP3"
$PN"EB2"49;
"UPI1_RX_DP4"
$PN"DW3"48;
"UPI1_RX_DP5"
$PN"DV2"47;
"UPI1_RX_DP6"
$PN"DR3"46;
"UPI1_RX_DP7"
$PN"DP2"45;
"UPI1_RX_DP8"
$PN"DM2"44;
"UPI1_RX_DP9"
$PN"DK2"43;
"UPI1_RX_DP10"
$PN"DH2"42;
"UPI1_RX_DP11"
$PN"DF2"41;
"UPI1_RX_DP12"
$PN"DC3"40;
"UPI1_RX_DP13"
$PN"DA1"39;
"UPI1_RX_DP14"
$PN"CW3"38;
"UPI1_RX_DP15"
$PN"CU1"37;
"UPI1_RX_DP16"
$PN"CT2"36;
"UPI1_RX_DP17"
$PN"CP2"35;
"UPI1_RX_DP18"
$PN"CM2"34;
"UPI1_RX_DP19"
$PN"CK2"33;
"UPI1_RX_DP20"
$PN"CG3"32;
"UPI1_RX_DP21"
$PN"CE1"31;
"UPI1_RX_DP22"
$PN"CC3"30;
"UPI1_RX_DP23"
$PN"BY2"29;
"UPI1_RX_DN0"
$PN"EH2"28;
"UPI1_RX_DN1"
$PN"EE3"27;
"UPI1_RX_DN2"
$PN"ED2"26;
"UPI1_RX_DN3"
$PN"EA1"25;
"UPI1_RX_DN4"
$PN"DY2"24;
"UPI1_RX_DN5"
$PN"DU1"23;
"UPI1_RX_DN6"
$PN"DT2"22;
"UPI1_RX_DN7"
$PN"DN1"21;
"UPI1_RX_DN8"
$PN"DL3"20;
"UPI1_RX_DN9"
$PN"DJ1"19;
"UPI1_RX_DN10"
$PN"DG3"18;
"UPI1_RX_DN11"
$PN"DE1"17;
"UPI1_RX_DN12"
$PN"DD2"16;
"UPI1_RX_DN13"
$PN"DB2"15;
"UPI1_RX_DN14"
$PN"CY2"14;
"UPI1_RX_DN15"
$PN"CV2"13;
"UPI1_RX_DN16"
$PN"CR3"12;
"UPI1_RX_DN17"
$PN"CN1"11;
"UPI1_RX_DN18"
$PN"CL3"10;
"UPI1_RX_DN19"
$PN"CJ1"9;
"UPI1_RX_DN20"
$PN"CH2"8;
"UPI1_RX_DN21"
$PN"CF2"7;
"UPI1_RX_DN22"
$PN"CD2"6;
"UPI1_RX_DN23"
$PN"CB2"5;
%"TAP"
"1","(-100,2525)","2","standard","I23";
;
CDS_LIB"standard"
BODY_TYPE"PLUMBING"
HDL_TAP"TRUE";
"B \NAC \NWC"4;
"S \NAC"
BN"20"8;
%"TAP"
"1","(-100,2575)","2","standard","I25";
;
CDS_LIB"standard"
BODY_TYPE"PLUMBING"
HDL_TAP"TRUE";
"B \NAC \NWC"4;
"S \NAC"
BN"21"7;
%"TAP"
"1","(-100,2625)","2","standard","I26";
;
CDS_LIB"standard"
BODY_TYPE"PLUMBING"
HDL_TAP"TRUE";
"B \NAC \NWC"4;
"S \NAC"
BN"22"6;
%"TAP"
"1","(-100,2775)","2","standard","I28";
;
CDS_LIB"standard"
BODY_TYPE"PLUMBING"
HDL_TAP"TRUE";
"B \NAC \NWC"3;
"S \NAC"
BN"0"52;
%"TAP"
"1","(-100,2825)","2","standard","I29";
;
CDS_LIB"standard"
BODY_TYPE"PLUMBING"
HDL_TAP"TRUE";
"B \NAC \NWC"3;
"S \NAC"
BN"1"51;
%"TAP"
"1","(-100,2875)","2","standard","I30";
;
CDS_LIB"standard"
BODY_TYPE"PLUMBING"
HDL_TAP"TRUE";
"B \NAC \NWC"3;
"S \NAC"
BN"2"50;
%"TAP"
"1","(-100,2925)","2","standard","I31";
;
CDS_LIB"standard"
BODY_TYPE"PLUMBING"
HDL_TAP"TRUE";
"B \NAC \NWC"3;
"S \NAC"
BN"3"49;
%"TAP"
"1","(-100,3025)","2","standard","I32";
;
CDS_LIB"standard"
BODY_TYPE"PLUMBING"
HDL_TAP"TRUE";
"B \NAC \NWC"3;
"S \NAC"
BN"5"47;
%"TAP"
"1","(-100,2975)","2","standard","I33";
;
CDS_LIB"standard"
BODY_TYPE"PLUMBING"
HDL_TAP"TRUE";
"B \NAC \NWC"3;
"S \NAC"
BN"4"48;
%"TAP"
"1","(-100,3075)","2","standard","I34";
;
CDS_LIB"standard"
BODY_TYPE"PLUMBING"
HDL_TAP"TRUE";
"B \NAC \NWC"3;
"S \NAC"
BN"6"46;
%"TAP"
"1","(-100,3125)","2","standard","I35";
;
CDS_LIB"standard"
BODY_TYPE"PLUMBING"
HDL_TAP"TRUE";
"B \NAC \NWC"3;
"S \NAC"
BN"7"45;
%"TAP"
"1","(-100,3175)","2","standard","I36";
;
CDS_LIB"standard"
BODY_TYPE"PLUMBING"
HDL_TAP"TRUE";
"B \NAC \NWC"3;
"S \NAC"
BN"8"44;
%"TAP"
"1","(-100,3225)","2","standard","I37";
;
CDS_LIB"standard"
BODY_TYPE"PLUMBING"
HDL_TAP"TRUE";
"B \NAC \NWC"3;
"S \NAC"
BN"9"43;
%"TAP"
"1","(-100,3275)","2","standard","I38";
;
CDS_LIB"standard"
BODY_TYPE"PLUMBING"
HDL_TAP"TRUE";
"B \NAC \NWC"3;
"S \NAC"
BN"10"42;
%"TAP"
"1","(-100,3325)","2","standard","I39";
;
CDS_LIB"standard"
BODY_TYPE"PLUMBING"
HDL_TAP"TRUE";
"B \NAC \NWC"3;
"S \NAC"
BN"11"41;
%"TAP"
"1","(-100,3475)","2","standard","I41";
;
CDS_LIB"standard"
BODY_TYPE"PLUMBING"
HDL_TAP"TRUE";
"B \NAC \NWC"3;
"S \NAC"
BN"14"38;
%"TAP"
"1","(-100,3575)","2","standard","I44";
;
CDS_LIB"standard"
BODY_TYPE"PLUMBING"
HDL_TAP"TRUE";
"B \NAC \NWC"3;
"S \NAC"
BN"16"36;
%"TAP"
"1","(-100,3625)","2","standard","I45";
;
CDS_LIB"standard"
BODY_TYPE"PLUMBING"
HDL_TAP"TRUE";
"B \NAC \NWC"3;
"S \NAC"
BN"17"35;
%"TAP"
"1","(-100,3675)","2","standard","I46";
;
CDS_LIB"standard"
BODY_TYPE"PLUMBING"
HDL_TAP"TRUE";
"B \NAC \NWC"3;
"S \NAC"
BN"18"34;
%"TAP"
"1","(-100,3725)","2","standard","I47";
;
CDS_LIB"standard"
BODY_TYPE"PLUMBING"
HDL_TAP"TRUE";
"B \NAC \NWC"3;
"S \NAC"
BN"19"33;
%"TAP"
"1","(-100,3925)","2","standard","I51";
;
CDS_LIB"standard"
BODY_TYPE"PLUMBING"
HDL_TAP"TRUE";
"B \NAC \NWC"3;
"S \NAC"
BN"23"29;
%"TAP"
"1","(3275,1525)","0","standard","I52";
;
CDS_LIB"standard"
BODY_TYPE"PLUMBING"
HDL_TAP"TRUE";
"B \NAC \NWC"2;
"S \NAC"
BN"0"76;
%"TAP"
"1","(3275,1575)","0","standard","I53";
;
CDS_LIB"standard"
BODY_TYPE"PLUMBING"
HDL_TAP"TRUE";
"B \NAC \NWC"2;
"S \NAC"
BN"1"75;
%"TAP"
"1","(3275,1625)","0","standard","I54";
;
CDS_LIB"standard"
BODY_TYPE"PLUMBING"
HDL_TAP"TRUE";
"B \NAC \NWC"2;
"S \NAC"
BN"2"74;
%"TAP"
"1","(3275,1675)","0","standard","I55";
;
CDS_LIB"standard"
BODY_TYPE"PLUMBING"
HDL_TAP"TRUE";
"B \NAC \NWC"2;
"S \NAC"
BN"3"73;
%"TAP"
"1","(3275,1825)","0","standard","I56";
;
CDS_LIB"standard"
BODY_TYPE"PLUMBING"
HDL_TAP"TRUE";
"B \NAC \NWC"2;
"S \NAC"
BN"6"70;
%"TAP"
"1","(3275,1875)","0","standard","I57";
;
CDS_LIB"standard"
BODY_TYPE"PLUMBING"
HDL_TAP"TRUE";
"B \NAC \NWC"2;
"S \NAC"
BN"7"69;
%"TAP"
"1","(3275,1725)","0","standard","I58";
;
CDS_LIB"standard"
BODY_TYPE"PLUMBING"
HDL_TAP"TRUE";
"B \NAC \NWC"2;
"S \NAC"
BN"4"72;
%"TAP"
"1","(3275,1775)","0","standard","I59";
;
CDS_LIB"standard"
BODY_TYPE"PLUMBING"
HDL_TAP"TRUE";
"B \NAC \NWC"2;
"S \NAC"
BN"5"71;
%"TAP"
"1","(3275,1975)","0","standard","I60";
;
CDS_LIB"standard"
BODY_TYPE"PLUMBING"
HDL_TAP"TRUE";
"B \NAC \NWC"2;
"S \NAC"
BN"9"67;
%"TAP"
"1","(3275,2125)","0","standard","I61";
;
CDS_LIB"standard"
BODY_TYPE"PLUMBING"
HDL_TAP"TRUE";
"B \NAC \NWC"2;
"S \NAC"
BN"12"64;
%"TAP"
"1","(3275,2075)","0","standard","I62";
;
CDS_LIB"standard"
BODY_TYPE"PLUMBING"
HDL_TAP"TRUE";
"B \NAC \NWC"2;
"S \NAC"
BN"11"65;
%"TAP"
"1","(3275,1925)","0","standard","I63";
;
CDS_LIB"standard"
BODY_TYPE"PLUMBING"
HDL_TAP"TRUE";
"B \NAC \NWC"2;
"S \NAC"
BN"8"68;
%"TAP"
"1","(3275,2025)","0","standard","I64";
;
CDS_LIB"standard"
BODY_TYPE"PLUMBING"
HDL_TAP"TRUE";
"B \NAC \NWC"2;
"S \NAC"
BN"10"66;
%"TAP"
"1","(3275,2225)","0","standard","I65";
;
CDS_LIB"standard"
BODY_TYPE"PLUMBING"
HDL_TAP"TRUE";
"B \NAC \NWC"2;
"S \NAC"
BN"14"62;
%"TAP"
"1","(3275,2375)","0","standard","I66";
;
CDS_LIB"standard"
BODY_TYPE"PLUMBING"
HDL_TAP"TRUE";
"B \NAC \NWC"2;
"S \NAC"
BN"17"59;
%"TAP"
"1","(3275,2325)","0","standard","I67";
;
CDS_LIB"standard"
BODY_TYPE"PLUMBING"
HDL_TAP"TRUE";
"B \NAC \NWC"2;
"S \NAC"
BN"16"60;
%"TAP"
"1","(3275,2175)","0","standard","I68";
;
CDS_LIB"standard"
BODY_TYPE"PLUMBING"
HDL_TAP"TRUE";
"B \NAC \NWC"2;
"S \NAC"
BN"13"63;
%"TAP"
"1","(3275,2275)","0","standard","I69";
;
CDS_LIB"standard"
BODY_TYPE"PLUMBING"
HDL_TAP"TRUE";
"B \NAC \NWC"2;
"S \NAC"
BN"15"61;
%"TAP"
"1","(3275,2575)","0","standard","I70";
;
CDS_LIB"standard"
BODY_TYPE"PLUMBING"
HDL_TAP"TRUE";
"B \NAC \NWC"2;
"S \NAC"
BN"21"55;
%"TAP"
"1","(3275,2625)","0","standard","I71";
;
CDS_LIB"standard"
BODY_TYPE"PLUMBING"
HDL_TAP"TRUE";
"B \NAC \NWC"2;
"S \NAC"
BN"22"54;
%"TAP"
"1","(3275,2525)","0","standard","I72";
;
CDS_LIB"standard"
BODY_TYPE"PLUMBING"
HDL_TAP"TRUE";
"B \NAC \NWC"2;
"S \NAC"
BN"20"56;
%"TAP"
"1","(3275,2475)","0","standard","I73";
;
CDS_LIB"standard"
BODY_TYPE"PLUMBING"
HDL_TAP"TRUE";
"B \NAC \NWC"2;
"S \NAC"
BN"19"57;
%"TAP"
"1","(3275,2425)","0","standard","I74";
;
CDS_LIB"standard"
BODY_TYPE"PLUMBING"
HDL_TAP"TRUE";
"B \NAC \NWC"2;
"S \NAC"
BN"18"58;
%"TAP"
"1","(3275,2775)","0","standard","I75";
;
CDS_LIB"standard"
BODY_TYPE"PLUMBING"
HDL_TAP"TRUE";
"B \NAC \NWC"1;
"S \NAC"
BN"0"100;
%"TAP"
"1","(3275,2875)","0","standard","I76";
;
CDS_LIB"standard"
BODY_TYPE"PLUMBING"
HDL_TAP"TRUE";
"B \NAC \NWC"1;
"S \NAC"
BN"2"98;
%"TAP"
"1","(3275,2825)","0","standard","I77";
;
CDS_LIB"standard"
BODY_TYPE"PLUMBING"
HDL_TAP"TRUE";
"B \NAC \NWC"1;
"S \NAC"
BN"1"99;
%"TAP"
"1","(3275,2675)","0","standard","I78";
;
CDS_LIB"standard"
BODY_TYPE"PLUMBING"
HDL_TAP"TRUE";
"B \NAC \NWC"2;
"S \NAC"
BN"23"53;
%"TAP"
"1","(3275,3125)","0","standard","I79";
;
CDS_LIB"standard"
BODY_TYPE"PLUMBING"
HDL_TAP"TRUE";
"B \NAC \NWC"1;
"S \NAC"
BN"7"93;
%"TAP"
"1","(3275,3075)","0","standard","I80";
;
CDS_LIB"standard"
BODY_TYPE"PLUMBING"
HDL_TAP"TRUE";
"B \NAC \NWC"1;
"S \NAC"
BN"6"94;
%"TAP"
"1","(3275,2975)","0","standard","I81";
;
CDS_LIB"standard"
BODY_TYPE"PLUMBING"
HDL_TAP"TRUE";
"B \NAC \NWC"1;
"S \NAC"
BN"4"96;
%"TAP"
"1","(3275,2925)","0","standard","I82";
;
CDS_LIB"standard"
BODY_TYPE"PLUMBING"
HDL_TAP"TRUE";
"B \NAC \NWC"1;
"S \NAC"
BN"3"97;
%"TAP"
"1","(3275,3025)","0","standard","I83";
;
CDS_LIB"standard"
BODY_TYPE"PLUMBING"
HDL_TAP"TRUE";
"B \NAC \NWC"1;
"S \NAC"
BN"5"95;
%"TAP"
"1","(3275,3325)","0","standard","I84";
;
CDS_LIB"standard"
BODY_TYPE"PLUMBING"
HDL_TAP"TRUE";
"B \NAC \NWC"1;
"S \NAC"
BN"11"89;
%"TAP"
"1","(3275,3375)","0","standard","I85";
;
CDS_LIB"standard"
BODY_TYPE"PLUMBING"
HDL_TAP"TRUE";
"B \NAC \NWC"1;
"S \NAC"
BN"12"88;
%"TAP"
"1","(3275,3175)","0","standard","I86";
;
CDS_LIB"standard"
BODY_TYPE"PLUMBING"
HDL_TAP"TRUE";
"B \NAC \NWC"1;
"S \NAC"
BN"8"92;
%"TAP"
"1","(3275,3275)","0","standard","I87";
;
CDS_LIB"standard"
BODY_TYPE"PLUMBING"
HDL_TAP"TRUE";
"B \NAC \NWC"1;
"S \NAC"
BN"10"90;
%"TAP"
"1","(3275,3225)","0","standard","I88";
;
CDS_LIB"standard"
BODY_TYPE"PLUMBING"
HDL_TAP"TRUE";
"B \NAC \NWC"1;
"S \NAC"
BN"9"91;
%"TAP"
"1","(3275,3425)","0","standard","I89";
;
CDS_LIB"standard"
BODY_TYPE"PLUMBING"
HDL_TAP"TRUE";
"B \NAC \NWC"1;
"S \NAC"
BN"13"87;
%"TAP"
"1","(3275,3525)","0","standard","I90";
;
CDS_LIB"standard"
BODY_TYPE"PLUMBING"
HDL_TAP"TRUE";
"B \NAC \NWC"1;
"S \NAC"
BN"15"85;
%"TAP"
"1","(3275,3475)","0","standard","I91";
;
CDS_LIB"standard"
BODY_TYPE"PLUMBING"
HDL_TAP"TRUE";
"B \NAC \NWC"1;
"S \NAC"
BN"14"86;
%"TAP"
"1","(3275,3575)","0","standard","I92";
;
CDS_LIB"standard"
BODY_TYPE"PLUMBING"
HDL_TAP"TRUE";
"B \NAC \NWC"1;
"S \NAC"
BN"16"84;
%"TAP"
"1","(3275,3625)","0","standard","I93";
;
CDS_LIB"standard"
BODY_TYPE"PLUMBING"
HDL_TAP"TRUE";
"B \NAC \NWC"1;
"S \NAC"
BN"17"83;
%"TAP"
"1","(3275,3675)","0","standard","I94";
;
CDS_LIB"standard"
BODY_TYPE"PLUMBING"
HDL_TAP"TRUE";
"B \NAC \NWC"1;
"S \NAC"
BN"18"82;
%"TAP"
"1","(3275,3925)","0","standard","I95";
;
CDS_LIB"standard"
BODY_TYPE"PLUMBING"
HDL_TAP"TRUE";
"B \NAC \NWC"1;
"S \NAC"
BN"23"77;
%"TAP"
"1","(3275,3875)","0","standard","I96";
;
CDS_LIB"standard"
BODY_TYPE"PLUMBING"
HDL_TAP"TRUE";
"B \NAC \NWC"1;
"S \NAC"
BN"22"78;
%"TAP"
"1","(3275,3825)","0","standard","I97";
;
CDS_LIB"standard"
BODY_TYPE"PLUMBING"
HDL_TAP"TRUE";
"B \NAC \NWC"1;
"S \NAC"
BN"21"79;
%"TAP"
"1","(3275,3725)","0","standard","I98";
;
CDS_LIB"standard"
BODY_TYPE"PLUMBING"
HDL_TAP"TRUE";
"B \NAC \NWC"1;
"S \NAC"
BN"19"81;
%"TAP"
"1","(3275,3775)","0","standard","I99";
;
CDS_LIB"standard"
BODY_TYPE"PLUMBING"
HDL_TAP"TRUE";
"B \NAC \NWC"1;
"S \NAC"
BN"20"80;
END.
